# Lightning U2 Carrier BOM.xlsx — BOM cost (bom)
| Wiwynn |  |  | BOM |  |  |  |  |  |  |  |  |  |  |  |  |  |  |  |  |  |  |  |  |  |  |  |  |  |  |  |
| Model: | Lightning HU-230L |  |  |  |  |  |  |  |  |  |  |  |  |  |  |  |  |  |  |  |  |  |  |  |  |  |  |  |  |  |
| Project Code.: BPD00Q010001 |  |  | Version:1.0 |  |  |  |  |  |  |  |  |  |  |  |  |  |  |  |  |  |  |  |  |  |  |  |  |  |  |  |
| Vendor: |  |  | 2016/01/06 |  |  |  |  |  |  |  |  | PVT |  |  |  |  |  |  |  |  |  |  |  |  |  |  |  |  |  |  |
| No | Level | Wistron Part Number | Description | Part Name | Picture | Q'ty for lower level | Unit Q'ty per system | Lyra Lite System Q'ty | Material/Finish | Type | Suppier | Tooling |  |  |  |  | NCT 300 sets |  | Breakeven  point per system | Hybrid | Remark |  |  |  |  |  |  |  |  |  |
|  |  |  |  |  |  |  |  |  |  | Assy/Metal/ Plastic/Purchase/Cable |  | New Tooling fee (USD) | Tooling modification fee (USD) | Existing tooling fee (USD) | U/P - tooling (USD) | tooled parts price per system (USD) | U/P - NCT (USD) | NCT parts price per system (USD) |  |  |  | 2D Drawing Release Day | Drawing Version | PDM | Design Frozen | PCC | Vendor | 發布 | Checking or completely | Checking or completely |
|  | 0 | DC.xxxxx.xxx |  |  |  | 1 | 1 | 1 |  |  |  |  |  |  |  |  |  |  |  |  |  |  |  |  |  | V |  |  |  |  |
| 1 | 1 | B60.00Q17.0001 | ASSY HDD CARRIER 7 LIGHTNING PVT |  |  | 1 | 1 |  |  | Assy |  |  |  |  |  |  |  |  |  |  |  |  |  |  |  |  |  |  |  |  |
| 2 | 2 | B42.00Q0I.0001 | CVR HDD CARRIER 7 LIGHTNING PVT | 13-000314 REV11 - WITH SPRING |  | 1 | 1 |  | JPSeco NFrPP325m | Plastic | UNEEC |  |  |  |  |  |  |  |  |  |  |  |  |  |  |  |  |  |  |  |
| 3 | 2 | B33.00Q0H.0001 | BRKT ROTARY HDD CARRIER BOT LIGHTNING |  |  | 1 | 1 |  | SGCC | Metal |  |  |  |  |  |  |  |  |  |  |  |  |  |  |  |  |  |  |  |  |
| 4 | 1 | 86.00Q25.547 | SCRW CAP M3*5L NI NYLOK |  |  | 4 | 4 |  |  | purchase |  |  |  |  |  |  |  |  |  |  |  |  |  |  |  |  |  |  |  |  |
| 1 | 1 | B42.00Q06.0001 | CVR M.2 LIGHTNING MOCKUP |  |  | 1 | 1 |  | JPSeco NFrPP325m #Burn M3-L4 nut * 2pcs | Plastic |  |  |  |  |  |  |  |  |  |  |  |  |  |  |  |  |  |  |  |  |
| 2 | 1 | B42.00Q07.0001 | CVR M.2 AIR DUCT TOP LIGHTNING MOCKUP |  |  | 1 | 1 |  | JPSeco NFrPP325m | Plastic |  |  |  |  |  |  |  |  |  |  |  |  |  |  |  |  |  |  |  |  |
| 3 | 1 | B42.00Q08.0001 | CVR M.2 AIR DUCT BTM LIGHTNING MOCKUP |  |  | 1 | 1 |  | JPSeco NFrPP325m | Plastic |  |  |  |  |  |  |  |  |  |  |  |  |  |  |  |  |  |  |  |  |
| 4 | 1 | 86.00Q25.547 | SCRW CAP M3*5L NI NYLOK |  |  | 2 | 2 |  |  | purchase |  |  |  |  |  |  |  |  |  |  |  |  |  |  |  |  |  |  |  |  |
| 4 | 2 | B47.00Q0B.0001 | SPONGE 15 HDD CARRIER LIGHTNING |  |  | 2 | 2 |  |  | Purchase |  |  |  |  |  |  |  |  |  |  |  |  |  |  |  |  |  |  |  |  |
| 5 | 2 | B42.00Q0J.0001 | LATCH ROTARY LIGHTNING PVT |  |  | 1 | 1 |  | JPSeco NFrPP325m | Plastic | UNEEC |  |  |  |  |  |  |  |  |  |  |  |  |  |  |  |  |  |  |  |
| 6 | 2 | 086.000H3.0545 | SCRW ROTARY SHOULDER LIGHTNING |  |  | 1 | 1 | 2 |  | Purchase | Wenhao |  |  |  |  |  |  |  |  |  |  | V |  |  |  | V | V |  |  |  |
|  |  |  |  |  |  |  |  | 1 |  |  |  |  |  |  |  |  |  |  |  |  |  |  |  |  |  | V | V |  |  |  |
|  |  |  |  |  |  |  |  | 1 |  |  |  |  |  |  |  |  |  |  |  |  |  | V |  |  |  | V | V |  |  |  |
|  |  |  |  |  |  |  |  |  |  |  |  |  |  |  |  |  |  |  |  |  |  |  |  |  |  | V | V |  |  |  |
|  |  |  |  |  |  |  |  |  |  |  |  |  |  |  |  |  |  |  |  |  |  | V |  |  |  | V | V |  |  |  |
|  |  |  |  |  |  |  |  |  |  |  |  |  |  |  |  |  |  |  |  |  |  |  |  |  |  | V | V |  |  |  |
|  |  |  |  |  |  |  |  |  |  |  |  |  |  |  |  |  |  |  |  |  |  | V |  |  |  | V | V |  |  |  |
|  |  |  |  |  |  |  |  |  |  |  |  |  |  |  |  |  |  |  |  |  |  | V |  |  |  | V | V |  |  |  |
|  |  |  |  |  |  |  |  |  |  |  |  |  |  |  |  |  |  |  |  |  |  |  |  |  |  | V | V |  |  |  |
|  |  |  |  |  |  |  |  | 4 |  |  |  |  |  |  |  |  |  |  |  |  |  |  |  |  |  | V | V |  |  |  |
|  |  |  |  |  |  |  |  | 1 |  |  |  |  |  |  |  |  |  |  |  |  |  |  |  |  |  | V | V |  |  |  |
|  |  |  |  |  |  |  |  | 2 |  |  |  |  |  |  |  |  |  |  |  |  |  |  |  |  |  | V | V |  |  |  |
|  |  |  |  |  |  |  |  | 4 |  |  |  |  |  |  |  |  |  |  |  |  |  |  |  |  |  | V | V |  |  |  |
|  |  |  |  |  |  |  |  | 1 |  |  |  |  |  |  |  |  |  |  |  |  |  |  |  |  |  | V | V |  |  |  |
|  |  |  |  |  |  |  |  | 10 |  |  |  |  |  |  |  |  |  |  |  |  |  |  |  |  |  | V | V |  |  |  |
|  |  |  |  |  |  |  |  | 1 |  |  |  |  |  |  |  |  |  |  |  |  |  |  |  |  |  |  |  |  |  |  |
|  |  |  |  |  |  |  |  | 1 |  |  |  |  |  |  |  |  |  |  |  |  |  |  |  |  |  |  |  |  |  |  |
|  |  |  |  |  |  |  |  | 1 |  |  |  |  |  |  |  |  |  |  |  |  |  |  |  |  |  |  |  |  |  |  |
|  |  |  |  |  |  |  |  | 1 |  |  |  |  |  |  |  |  |  |  |  |  |  | v |  |  |  | V | V |  |  |  |
|  |  |  |  |  |  |  |  | 1 |  |  |  |  |  |  |  |  |  |  |  |  |  | v |  |  |  | V | V |  |  |  |
|  |  |  |  |  |  |  |  | 1 |  |  |  |  |  |  |  |  |  |  |  |  |  |  |  |  |  | V | V |  |  |  |
|  |  |  |  |  |  |  |  | 1 |  |  |  |  |  |  |  |  |  |  |  |  |  |  |  |  |  | V | V |  |  |  |
|  |  |  |  |  |  |  |  | 1 |  |  |  |  |  |  |  |  |  |  |  |  |  | v |  |  |  | V | V |  |  |  |
|  |  |  |  |  |  |  |  | 1 |  |  |  |  |  |  |  |  |  |  |  |  |  | v |  |  |  | V | V |  |  |  |
|  |  |  |  |  |  |  |  | 1 |  |  |  |  |  |  |  |  |  |  |  |  |  | v |  |  |  | V | V |  |  |  |
|  |  |  |  |  |  |  |  | 1 |  |  |  |  |  |  |  |  |  |  |  |  |  |  |  |  |  | V | V |  |  |  |
|  |  |  |  |  |  |  |  | 1 |  |  |  |  |  |  |  |  |  |  |  |  |  | v |  |  |  | V | V |  |  |  |
|  |  |  |  |  |  |  |  | 2 |  |  |  |  |  |  |  |  |  |  |  |  |  |  |  |  |  | V | V |  |  |  |
|  |  |  |  |  |  |  |  | 1 |  |  |  |  |  |  |  |  |  |  |  |  |  | v |  |  |  | V | V |  |  |  |
|  |  |  |  |  |  |  |  | 1 |  |  |  |  |  |  |  |  |  |  |  |  |  | v |  |  |  | V | V |  |  |  |
|  |  |  |  |  |  |  |  | 0 |  |  |  |  |  |  |  |  |  |  |  |  |  |  |  |  |  | V | V |  |  |  |
|  |  |  |  |  |  |  |  | 1 |  |  |  |  |  |  |  |  |  |  |  |  |  |  |  |  |  |  |  |  |  |  |
|  |  |  |  |  |  |  |  | 1 |  |  |  |  |  |  |  |  |  |  |  |  |  |  |  |  |  |  |  |  |  |  |
|  |  |  |  |  |  |  |  | 1 |  |  |  |  |  |  |  |  |  |  |  |  |  |  |  |  |  |  |  |  |  |  |
|  |  |  |  |  |  |  |  | 1 |  |  |  |  |  |  |  |  |  |  |  |  |  |  |  |  |  | V | V |  |  |  |
|  |  |  |  |  |  |  |  | 1 |  |  |  |  |  |  |  |  |  |  |  |  |  |  |  |  |  | V | V |  |  |  |
|  |  |  |  |  |  |  |  | 1 |  |  |  |  |  |  |  |  |  |  |  |  |  |  |  |  |  | V | V |  |  |  |
|  |  |  |  |  |  |  |  | 1 |  |  |  |  |  |  |  |  |  |  |  |  |  |  |  |  |  | V | V |  |  |  |
|  |  |  |  |  |  |  |  | 1 |  |  |  |  |  |  |  |  |  |  |  |  |  |  |  |  |  | V | V |  |  |  |
|  |  |  |  |  |  |  |  | 1 |  |  |  |  |  |  |  |  |  |  |  |  |  |  |  |  |  | V | V |  |  |  |
|  |  |  |  |  |  |  |  | 1 |  |  |  |  |  |  |  |  |  |  |  |  |  |  |  |  |  | V | V |  |  |  |
|  |  |  |  |  |  |  |  | 1 |  |  |  |  |  |  |  |  |  |  |  |  |  |  |  |  |  | V | V |  |  |  |
|  |  |  |  |  |  |  |  | 2 |  |  |  |  |  |  |  |  |  |  |  |  |  |  |  |  |  | V | V |  |  |  |
|  |  |  |  |  |  |  |  | 1 |  |  |  |  |  |  |  |  |  |  |  |  |  |  |  |  |  | V | V |  |  |  |
|  |  |  |  |  |  |  |  | 1 |  |  |  |  |  |  |  |  |  |  |  |  |  |  |  |  |  | V | V |  |  |  |
|  |  |  |  |  |  |  |  |  |  |  |  |  |  |  | Currency(USD) |  |  |  |  |  |  |  |  |  |  |  |  |  |  |  |
|  |  |  |  |  |  |  |  |  |  |  |  |  | Metal |  |  | 0 |  |  |  |  |  |  |  |  |  |  |  |  |  |  |
|  |  |  |  |  |  |  |  |  |  |  |  |  | Plastic(Fan duct) |  |  | 0 |  |  |  |  |  |  |  |  |  |  |  |  |  |  |
|  |  |  |  |  |  |  |  |  |  |  |  |  | Purchase |  |  | 0 |  |  |  |  |  |  |  |  |  |  |  |  |  |  |
|  |  |  |  |  |  |  |  |  |  |  |  |  | Tray (Q'ty:10) |  |  | 20.115122129578801 |  |  |  |  |  |  |  |  |  |  |  |  |  |  |
|  |  |  |  |  |  |  |  |  |  |  |  |  | Ass'y |  |  | #REF! |  |  |  |  |  |  |  |  |  |  |  |  |  |  |
|  |  |  |  |  |  |  |  |  |  |  |  |  | Packing |  |  | #REF! |  |  |  |  |  |  |  |  |  |  |  |  |  |  |
|  |  |  |  |  |  |  |  |  |  |  |  |  | Transportation |  |  | #REF! |  |  |  |  |  |  |  |  |  |  |  |  |  |  |
|  |  |  |  |  |  |  |  |  |  |  |  |  | Parts total |  |  | #REF! |  |  |  |  |  |  |  |  |  |  |  |  |  |  |
|  |  |  |  |  |  |  |  |  |  |  |  |  | New Tooling for Lyra(M) |  |  | 0 |  |  |  |  |  |  |  |  |  |  |  |  |  |  |
|  |  |  |  |  |  |  |  |  |  |  |  |  | New Tooling for Lyra(P) |  |  | 0 |  |  |  |  |  |  |  |  |  |  |  |  |  |  |
|  |  |  |  |  |  |  |  |  |  |  |  |  | Tooling modification for Lyra |  |  | 0 |  |  |  |  |  |  |  |  |  |  |  |  |  |  |
|  |  |  |  |  |  |  |  |  |  |  |  |  | Tooling Total |  |  | 0 |  |  |  |  |  |  |  |  |  |  |  |  |  |  |
